# S9S_MB_2U (Grand Teton) — schematic netlist excerpt (pin names and nets, part order shuffled) for the footprints in the layout excerpt that follows; sources: Cadence DE-HDL packaged netlist, KiCad conversion of 03242023_DA0F0TMBIJ0_F0T_Motherboard_J_brd_V01_OCP.brd

PJ63  Q_SHORT  EMPTY  pkg SM  page 262 : \1\ = SH_P1V05_PCH_AUX_N ; \2\ = GND
PR4232  Q_RES  0 5% CHIP  pkg 0402LF  page 278 : A = NC_PVCCD_HV_CPU0_ACSP4 ; B = GND
R837  Q_RES  0 5% CHIP  pkg 0402LF  page 129 : A = RST_PLD_CPU0_DRAM_CD_N ; B = RST_M_CD_CPU0_FPGA_N

(kicad_pcb
	(version 20260206)
	(generator "pcbnew")
	(generator_version "10.0")
	(general
		(thickness 1.6)
		(legacy_teardrops no)
	)
	(paper "A4")
	(title_block
		(title "03242023_DA0F0TMBIJ0_F0T_Motherboard_J_brd_V01_OCP.brd")
		(comment 1 "Grand Teton / footprints 6002-6004 of 6105")
	)
	(layers
		(0 "F.Cu" signal "TOP")
		(4 "In1.Cu" signal "GND")
		(6 "In2.Cu" signal "IN1")
		(8 "In3.Cu" signal "GND1")
		(10 "In4.Cu" signal "IN2")
		(12 "In5.Cu" signal "GND2")
		(14 "In6.Cu" signal "IN3")
		(16 "In7.Cu" signal "GND3")
		(18 "In8.Cu" signal "VCC")
		(20 "In9.Cu" signal "VCC1")
		(22 "In10.Cu" signal "GND4")
		(24 "In11.Cu" signal "IN4")
		(26 "In12.Cu" signal "GND5")
		(28 "In13.Cu" signal "IN5")
		(30 "In14.Cu" signal "GND6")
		(32 "In15.Cu" signal "IN6")
		(34 "In16.Cu" signal "GND7")
		(2 "B.Cu" signal "BOTTOM")
		(9 "F.Adhes" user "F.Adhesive")
		(11 "B.Adhes" user "B.Adhesive")
		(13 "F.Paste" user "Package Geometry/Pastemask Top")
		(15 "B.Paste" user "Package Geometry/Pastemask Bottom")
		(5 "F.SilkS" user "Ref Des/Silkscreen Top")
		(7 "B.SilkS" user "Ref Des/Silkscreen Bottom")
		(1 "F.Mask" user "Board Geometry/Soldermask Top")
		(3 "B.Mask" user "Board Geometry/Soldermask Bottom")
		(17 "Dwgs.User" user "User.Drawings")
		(19 "Cmts.User" user "User.Comments")
		(21 "Eco1.User" user "User.Eco1")
		(23 "Eco2.User" user "User.Eco2")
		(25 "Edge.Cuts" user "Board Geometry/Outline")
		(27 "Margin" user)
		(31 "F.CrtYd" user "Package Geometry/Place Bound Top")
		(29 "B.CrtYd" user "Package Geometry/Place Bound Bottom")
		(35 "F.Fab" user "Ref Des/Assembly Top")
		(33 "B.Fab" user "Ref Des/Assembly Bottom")
	)
	(footprint ""
		(layer "B.Cu")
		(at 269.684246 -193.503296 -90)
		(property "Reference" "R837"
			(at 0 0 90)
			(layer "B.SilkS")
			(hide yes)
			(effects
				(font
					(size 1.27 1.27)
				)
				(justify mirror)
			)
		)
		(property "Value" ""
			(at 0 0 90)
			(layer "B.Fab")
			(effects
				(font
					(size 1.27 1.27)
				)
				(justify mirror)
			)
		)
		(duplicate_pad_numbers_are_jumpers no)
		(fp_line
			(start -0.7874 0.4064)
			(end 0.7874 0.4064)
			(stroke
				(width 0.1524)
				(type default)
			)
			(layer "B.SilkS")
		)
		(fp_line
			(start 0.7874 0.4064)
			(end 0.7874 -0.4064)
			(stroke
				(width 0.1524)
				(type default)
			)
			(layer "B.SilkS")
		)
		(fp_line
			(start -0.7874 -0.4064)
			(end -0.7874 0.4064)
			(stroke
				(width 0.1524)
				(type default)
			)
			(layer "B.SilkS")
		)
		(fp_line
			(start 0.7874 -0.4064)
			(end -0.7874 -0.4064)
			(stroke
				(width 0.1524)
				(type default)
			)
			(layer "B.SilkS")
		)
		(fp_line
			(start -0.67945 0.3048)
			(end -0.120396 0.3048)
			(stroke
				(width 0.1)
				(type default)
			)
			(layer "B.Fab")
		)
		(fp_line
			(start -0.120396 0.3048)
			(end -0.120396 0.2794)
			(stroke
				(width 0.1)
				(type default)
			)
			(layer "B.Fab")
		)
		(fp_line
			(start 0.12065 0.3048)
			(end 0.67945 0.3048)
			(stroke
				(width 0.1)
				(type default)
			)
			(layer "B.Fab")
		)
		(fp_line
			(start 0.67945 0.3048)
			(end 0.67945 -0.305054)
			(stroke
				(width 0.1)
				(type default)
			)
			(layer "B.Fab")
		)
		(fp_line
			(start -0.120396 0.2794)
			(end 0.12065 0.2794)
			(stroke
				(width 0.1)
				(type default)
			)
			(layer "B.Fab")
		)
		(fp_line
			(start 0.12065 0.2794)
			(end 0.12065 0.3048)
			(stroke
				(width 0.1)
				(type default)
			)
			(layer "B.Fab")
		)
		(fp_line
			(start -0.12065 -0.2794)
			(end -0.12065 -0.3048)
			(stroke
				(width 0.1)
				(type default)
			)
			(layer "B.Fab")
		)
		(fp_line
			(start 0.12065 -0.2794)
			(end -0.12065 -0.2794)
			(stroke
				(width 0.1)
				(type default)
			)
			(layer "B.Fab")
		)
		(fp_line
			(start -0.67945 -0.3048)
			(end -0.67945 0.3048)
			(stroke
				(width 0.1)
				(type default)
			)
			(layer "B.Fab")
		)
		(fp_line
			(start -0.12065 -0.3048)
			(end -0.67945 -0.3048)
			(stroke
				(width 0.1)
				(type default)
			)
			(layer "B.Fab")
		)
		(fp_line
			(start 0.12065 -0.305054)
			(end 0.12065 -0.2794)
			(stroke
				(width 0.1)
				(type default)
			)
			(layer "B.Fab")
		)
		(fp_line
			(start 0.67945 -0.305054)
			(end 0.12065 -0.305054)
			(stroke
				(width 0.1)
				(type default)
			)
			(layer "B.Fab")
		)
		(pad "1" smd circle
			(at 0.40005 0 90)
			(size 0 0)
			(layers "B.Cu" "B.Mask" "B.Paste")
			(net "RST_PLD_CPU0_DRAM_CD_N")
		)
		(pad "2" smd circle
			(at -0.40005 0 90)
			(size 0 0)
			(layers "B.Cu" "B.Mask" "B.Paste")
			(net "RST_M_CD_CPU0_FPGA_N")
		)
	)
	(footprint ""
		(layer "B.Cu")
		(at 434.77688 -124.932948 90)
		(property "Reference" "PR4232"
			(at 0 0 90)
			(layer "B.SilkS")
			(hide yes)
			(effects
				(font
					(size 1.27 1.27)
				)
				(justify mirror)
			)
		)
		(property "Value" ""
			(at 0 0 90)
			(layer "B.Fab")
			(effects
				(font
					(size 1.27 1.27)
				)
				(justify mirror)
			)
		)
		(duplicate_pad_numbers_are_jumpers no)
		(fp_line
			(start 0.7874 -0.4064)
			(end -0.7874 -0.4064)
			(stroke
				(width 0.1524)
				(type default)
			)
			(layer "B.SilkS")
		)
		(fp_line
			(start -0.7874 -0.4064)
			(end -0.7874 0.4064)
			(stroke
				(width 0.1524)
				(type default)
			)
			(layer "B.SilkS")
		)
		(fp_line
			(start 0.7874 0.4064)
			(end 0.7874 -0.4064)
			(stroke
				(width 0.1524)
				(type default)
			)
			(layer "B.SilkS")
		)
		(fp_line
			(start -0.7874 0.4064)
			(end 0.7874 0.4064)
			(stroke
				(width 0.1524)
				(type default)
			)
			(layer "B.SilkS")
		)
		(fp_line
			(start 0.67945 -0.305054)
			(end 0.12065 -0.305054)
			(stroke
				(width 0.1)
				(type default)
			)
			(layer "B.Fab")
		)
		(fp_line
			(start 0.12065 -0.305054)
			(end 0.12065 -0.2794)
			(stroke
				(width 0.1)
				(type default)
			)
			(layer "B.Fab")
		)
		(fp_line
			(start -0.12065 -0.3048)
			(end -0.67945 -0.3048)
			(stroke
				(width 0.1)
				(type default)
			)
			(layer "B.Fab")
		)
		(fp_line
			(start -0.67945 -0.3048)
			(end -0.67945 0.3048)
			(stroke
				(width 0.1)
				(type default)
			)
			(layer "B.Fab")
		)
		(fp_line
			(start 0.12065 -0.2794)
			(end -0.12065 -0.2794)
			(stroke
				(width 0.1)
				(type default)
			)
			(layer "B.Fab")
		)
		(fp_line
			(start -0.12065 -0.2794)
			(end -0.12065 -0.3048)
			(stroke
				(width 0.1)
				(type default)
			)
			(layer "B.Fab")
		)
		(fp_line
			(start 0.12065 0.2794)
			(end 0.12065 0.3048)
			(stroke
				(width 0.1)
				(type default)
			)
			(layer "B.Fab")
		)
		(fp_line
			(start -0.120396 0.2794)
			(end 0.12065 0.2794)
			(stroke
				(width 0.1)
				(type default)
			)
			(layer "B.Fab")
		)
		(fp_line
			(start 0.67945 0.3048)
			(end 0.67945 -0.305054)
			(stroke
				(width 0.1)
				(type default)
			)
			(layer "B.Fab")
		)
		(fp_line
			(start 0.12065 0.3048)
			(end 0.67945 0.3048)
			(stroke
				(width 0.1)
				(type default)
			)
			(layer "B.Fab")
		)
		(fp_line
			(start -0.120396 0.3048)
			(end -0.120396 0.2794)
			(stroke
				(width 0.1)
				(type default)
			)
			(layer "B.Fab")
		)
		(fp_line
			(start -0.67945 0.3048)
			(end -0.120396 0.3048)
			(stroke
				(width 0.1)
				(type default)
			)
			(layer "B.Fab")
		)
		(pad "1" smd circle
			(at 0.40005 0 270)
			(size 0 0)
			(layers "B.Cu" "B.Mask" "B.Paste")
			(net "NC_PVCCD_HV_CPU0_ACSP4")
		)
		(pad "2" smd circle
			(at -0.40005 0 270)
			(size 0 0)
			(layers "B.Cu" "B.Mask" "B.Paste")
			(net "GND")
		)
	)
	(footprint ""
		(layer "B.Cu")
		(at 325.688706 -74.871072 180)
		(property "Reference" "PJ63"
			(at -1.089914 1.737106 0)
			(unlocked yes)
			(layer "B.SilkS")
			(effects
				(font
					(size 0.7874 0.5842)
					(thickness 0.1524)
				)
				(justify left mirror)
			)
		)
		(property "Value" ""
			(at 0 0 0)
			(layer "B.Fab")
			(effects
				(font
					(size 1.27 1.27)
				)
				(justify mirror)
			)
		)
		(duplicate_pad_numbers_are_jumpers no)
		(pad "1" smd circle
			(at 0.7493 0 270)
			(size 0 0)
			(layers "B.Cu" "B.Mask" "B.Paste")
			(net "SH_P1V05_PCH_AUX_N")
		)
		(pad "2" smd rect
			(at -0.7493 0 90)
			(size 0.7112 0.8128)
			(layers "B.Cu" "B.Mask" "B.Paste")
			(net "GND")
		)
		(zone
			(layer "B.Cu")
			(hatch none 0.5)
			(connect_pads
				(clearance 0)
			)
			(min_thickness 0.25)
			(keepout
				(tracks allowed)
				(vias not_allowed)
				(pads allowed)
				(copperpour not_allowed)
				(footprints allowed)
			)
			(placement
				(enabled no)
				(sheetname "")
			)
			(fill
				(thermal_gap 0.5)
				(thermal_bridge_width 0.5)
				(island_removal_mode 0)
			)
			(polygon
				(pts
					(xy 324.507606 -75.282552) (xy 324.507606 -74.464926) (xy 326.895206 -74.464926) (xy 326.895206 -75.282552)
				)
			)
		)
	)
)
